# S9S_MB_2U (Grand Teton) — schematic netlist excerpt (pin names and nets, part order shuffled) for the footprints in the layout excerpt that follows; sources: Cadence DE-HDL packaged netlist, KiCad conversion of 03242023_DA0F0TMBIJ0_F0T_Motherboard_J_brd_V01_OCP.brd

PC230_P0_8  Q_CAP  3300PF 50V 10% X7R  pkg 0402  page 270 : A = SW_P12V_PVCCIN_CPU0_FLT ; B = GND
R4671  Q_RES  10K 1% EMPTY  pkg 0402LF  page 306 : A = P3V3_AUX ; B = HSC_D_OC

(kicad_pcb
	(version 20260206)
	(generator "pcbnew")
	(generator_version "10.0")
	(general
		(thickness 1.6)
		(legacy_teardrops no)
	)
	(paper "A4")
	(title_block
		(title "03242023_DA0F0TMBIJ0_F0T_Motherboard_J_brd_V01_OCP.brd")
		(comment 1 "Grand Teton / footprints 2783-2784 of 6105")
	)
	(layers
		(0 "F.Cu" signal "TOP")
		(4 "In1.Cu" signal "GND")
		(6 "In2.Cu" signal "IN1")
		(8 "In3.Cu" signal "GND1")
		(10 "In4.Cu" signal "IN2")
		(12 "In5.Cu" signal "GND2")
		(14 "In6.Cu" signal "IN3")
		(16 "In7.Cu" signal "GND3")
		(18 "In8.Cu" signal "VCC")
		(20 "In9.Cu" signal "VCC1")
		(22 "In10.Cu" signal "GND4")
		(24 "In11.Cu" signal "IN4")
		(26 "In12.Cu" signal "GND5")
		(28 "In13.Cu" signal "IN5")
		(30 "In14.Cu" signal "GND6")
		(32 "In15.Cu" signal "IN6")
		(34 "In16.Cu" signal "GND7")
		(2 "B.Cu" signal "BOTTOM")
		(9 "F.Adhes" user "F.Adhesive")
		(11 "B.Adhes" user "B.Adhesive")
		(13 "F.Paste" user "Package Geometry/Pastemask Top")
		(15 "B.Paste" user "Package Geometry/Pastemask Bottom")
		(5 "F.SilkS" user "Ref Des/Silkscreen Top")
		(7 "B.SilkS" user "Ref Des/Silkscreen Bottom")
		(1 "F.Mask" user "Board Geometry/Soldermask Top")
		(3 "B.Mask" user "Board Geometry/Soldermask Bottom")
		(17 "Dwgs.User" user "User.Drawings")
		(19 "Cmts.User" user "User.Comments")
		(21 "Eco1.User" user "User.Eco1")
		(23 "Eco2.User" user "User.Eco2")
		(25 "Edge.Cuts" user "Board Geometry/Outline")
		(27 "Margin" user)
		(31 "F.CrtYd" user "Package Geometry/Place Bound Top")
		(29 "B.CrtYd" user "Package Geometry/Place Bound Bottom")
		(35 "F.Fab" user "Ref Des/Assembly Top")
		(33 "B.Fab" user "Ref Des/Assembly Bottom")
	)
	(footprint ""
		(layer "F.Cu")
		(at 390.42594 -343.018872 -90)
		(property "Reference" "PC230_P0_8"
			(at 0 0 270)
			(layer "F.SilkS")
			(hide yes)
			(effects
				(font
					(size 1.27 1.27)
				)
			)
		)
		(property "Value" ""
			(at 0 0 270)
			(layer "F.Fab")
			(effects
				(font
					(size 1.27 1.27)
				)
			)
		)
		(duplicate_pad_numbers_are_jumpers no)
		(fp_line
			(start -0.7874 0.4064)
			(end -0.7874 -0.4064)
			(stroke
				(width 0.1524)
				(type default)
			)
			(layer "F.SilkS")
		)
		(fp_line
			(start 0.7874 0.4064)
			(end -0.7874 0.4064)
			(stroke
				(width 0.1524)
				(type default)
			)
			(layer "F.SilkS")
		)
		(fp_line
			(start -0.7874 -0.4064)
			(end 0.7874 -0.4064)
			(stroke
				(width 0.1524)
				(type default)
			)
			(layer "F.SilkS")
		)
		(fp_line
			(start 0.7874 -0.4064)
			(end 0.7874 0.4064)
			(stroke
				(width 0.1524)
				(type default)
			)
			(layer "F.SilkS")
		)
		(fp_line
			(start -0.67945 0.3048)
			(end -0.67945 -0.305054)
			(stroke
				(width 0.1)
				(type default)
			)
			(layer "F.Fab")
		)
		(fp_line
			(start -0.12065 0.3048)
			(end -0.67945 0.3048)
			(stroke
				(width 0.1)
				(type default)
			)
			(layer "F.Fab")
		)
		(fp_line
			(start 0.120396 0.3048)
			(end 0.120396 0.2794)
			(stroke
				(width 0.1)
				(type default)
			)
			(layer "F.Fab")
		)
		(fp_line
			(start 0.67945 0.3048)
			(end 0.120396 0.3048)
			(stroke
				(width 0.1)
				(type default)
			)
			(layer "F.Fab")
		)
		(fp_line
			(start -0.12065 0.2794)
			(end -0.12065 0.3048)
			(stroke
				(width 0.1)
				(type default)
			)
			(layer "F.Fab")
		)
		(fp_line
			(start 0.120396 0.2794)
			(end -0.12065 0.2794)
			(stroke
				(width 0.1)
				(type default)
			)
			(layer "F.Fab")
		)
		(fp_line
			(start -0.12065 -0.2794)
			(end 0.12065 -0.2794)
			(stroke
				(width 0.1)
				(type default)
			)
			(layer "F.Fab")
		)
		(fp_line
			(start 0.12065 -0.2794)
			(end 0.12065 -0.3048)
			(stroke
				(width 0.1)
				(type default)
			)
			(layer "F.Fab")
		)
		(fp_line
			(start 0.12065 -0.3048)
			(end 0.67945 -0.3048)
			(stroke
				(width 0.1)
				(type default)
			)
			(layer "F.Fab")
		)
		(fp_line
			(start 0.67945 -0.3048)
			(end 0.67945 0.3048)
			(stroke
				(width 0.1)
				(type default)
			)
			(layer "F.Fab")
		)
		(fp_line
			(start -0.67945 -0.305054)
			(end -0.12065 -0.305054)
			(stroke
				(width 0.1)
				(type default)
			)
			(layer "F.Fab")
		)
		(fp_line
			(start -0.12065 -0.305054)
			(end -0.12065 -0.2794)
			(stroke
				(width 0.1)
				(type default)
			)
			(layer "F.Fab")
		)
		(pad "1" smd circle
			(at -0.40005 0 270)
			(size 0 0)
			(layers "F.Cu" "F.Mask" "F.Paste")
			(net "SW_P12V_PVCCIN_CPU0_FLT")
		)
		(pad "2" smd circle
			(at 0.40005 0 270)
			(size 0 0)
			(layers "F.Cu" "F.Mask" "F.Paste")
			(net "GND")
		)
	)
	(footprint ""
		(layer "F.Cu")
		(at 276.80666 -424.424602 180)
		(property "Reference" "R4671"
			(at 0 0 180)
			(layer "F.SilkS")
			(hide yes)
			(effects
				(font
					(size 1.27 1.27)
				)
			)
		)
		(property "Value" ""
			(at 0 0 180)
			(layer "F.Fab")
			(effects
				(font
					(size 1.27 1.27)
				)
			)
		)
		(duplicate_pad_numbers_are_jumpers no)
		(fp_line
			(start 0.7874 0.4064)
			(end -0.7874 0.4064)
			(stroke
				(width 0.1524)
				(type default)
			)
			(layer "F.SilkS")
		)
		(fp_line
			(start 0.7874 -0.4064)
			(end 0.7874 0.4064)
			(stroke
				(width 0.1524)
				(type default)
			)
			(layer "F.SilkS")
		)
		(fp_line
			(start -0.7874 0.4064)
			(end -0.7874 -0.4064)
			(stroke
				(width 0.1524)
				(type default)
			)
			(layer "F.SilkS")
		)
		(fp_line
			(start -0.7874 -0.4064)
			(end 0.7874 -0.4064)
			(stroke
				(width 0.1524)
				(type default)
			)
			(layer "F.SilkS")
		)
		(fp_line
			(start 0.67945 0.3048)
			(end 0.120396 0.3048)
			(stroke
				(width 0.1)
				(type default)
			)
			(layer "F.Fab")
		)
		(fp_line
			(start 0.67945 -0.3048)
			(end 0.67945 0.3048)
			(stroke
				(width 0.1)
				(type default)
			)
			(layer "F.Fab")
		)
		(fp_line
			(start 0.12065 -0.2794)
			(end 0.12065 -0.3048)
			(stroke
				(width 0.1)
				(type default)
			)
			(layer "F.Fab")
		)
		(fp_line
			(start 0.12065 -0.3048)
			(end 0.67945 -0.3048)
			(stroke
				(width 0.1)
				(type default)
			)
			(layer "F.Fab")
		)
		(fp_line
			(start 0.120396 0.3048)
			(end 0.120396 0.2794)
			(stroke
				(width 0.1)
				(type default)
			)
			(layer "F.Fab")
		)
		(fp_line
			(start 0.120396 0.2794)
			(end -0.12065 0.2794)
			(stroke
				(width 0.1)
				(type default)
			)
			(layer "F.Fab")
		)
		(fp_line
			(start -0.12065 0.3048)
			(end -0.67945 0.3048)
			(stroke
				(width 0.1)
				(type default)
			)
			(layer "F.Fab")
		)
		(fp_line
			(start -0.12065 0.2794)
			(end -0.12065 0.3048)
			(stroke
				(width 0.1)
				(type default)
			)
			(layer "F.Fab")
		)
		(fp_line
			(start -0.12065 -0.2794)
			(end 0.12065 -0.2794)
			(stroke
				(width 0.1)
				(type default)
			)
			(layer "F.Fab")
		)
		(fp_line
			(start -0.12065 -0.305054)
			(end -0.12065 -0.2794)
			(stroke
				(width 0.1)
				(type default)
			)
			(layer "F.Fab")
		)
		(fp_line
			(start -0.67945 0.3048)
			(end -0.67945 -0.305054)
			(stroke
				(width 0.1)
				(type default)
			)
			(layer "F.Fab")
		)
		(fp_line
			(start -0.67945 -0.305054)
			(end -0.12065 -0.305054)
			(stroke
				(width 0.1)
				(type default)
			)
			(layer "F.Fab")
		)
		(pad "1" smd circle
			(at -0.40005 0 180)
			(size 0 0)
			(layers "F.Cu" "F.Mask" "F.Paste")
			(net "P3V3_AUX")
		)
		(pad "2" smd circle
			(at 0.40005 0 180)
			(size 0 0)
			(layers "F.Cu" "F.Mask" "F.Paste")
			(net "HSC_D_OC")
		)
	)
)
